# T6G (Grand Teton) — schematic netlist excerpt (pin names and nets, part order shuffled) for the footprints in the layout excerpt that follows; sources: Cadence DE-HDL packaged netlist, KiCad conversion of 04192023_DAF0TMB3IC0_F0TG_MB_C_brd_V02_OCP.brd

J108  CONN112_10137002101LF  CONN112_10137002-101LF IO  pkg HSD_F112D8_P2W1-2_RDH  page 118
  A1  = GPU_3V3IO_RSVD3_FFU
  A2  = GND
  A3  = PRSNT_CABLE_GPU_A2_N
  A4  = GND
  A5  = GPU_3V3IO_RSVD5_FFU
  A6  = GND
  A7  = GPU_FPGA_OVERT_N
  A8  = GND
  B1  = GND
  B2  = P5E_CPU0_P0_RX_BUF_DN<1>
  B3  = GND
  B4  = P5E_CPU0_P0_RX_BUF_DN<3>
  B5  = GND
  B6  = P5E_CPU0_P0_RX_BUF_DN<5>
  B7  = GND
  B8  = P5E_CPU0_P0_RX_BUF_DN<7>
  C1  = P5E_CPU0_P0_RX_BUF_DN<0>
  C2  = P5E_CPU0_P0_RX_BUF_DP<1>
  C3  = P5E_CPU0_P0_RX_BUF_DN<2>
  C4  = P5E_CPU0_P0_RX_BUF_DP<3>
  C5  = P5E_CPU0_P0_RX_BUF_DN<4>
  C6  = P5E_CPU0_P0_RX_BUF_DP<5>
  C7  = P5E_CPU0_P0_RX_BUF_DN<6>
  C8  = P5E_CPU0_P0_RX_BUF_DP<7>
  D1  = P5E_CPU0_P0_RX_BUF_DP<0>
  D2  = GND
  D3  = P5E_CPU0_P0_RX_BUF_DP<2>
  D4  = GND
  D5  = P5E_CPU0_P0_RX_BUF_DP<4>
  D6  = GND
  D7  = P5E_CPU0_P0_RX_BUF_DP<6>
  D8  = GND
  E1  = GND
  E2  = P5E_CPU0_P1_RX_BUF_DN<1>
  E3  = GND
  E4  = P5E_CPU0_P1_RX_BUF_DN<3>
  E5  = GND
  E6  = P5E_CPU0_P1_RX_BUF_DN<5>
  E7  = GND
  E8  = P5E_CPU0_P1_RX_BUF_DN<7>
  F1  = P5E_CPU0_P1_RX_BUF_DN<0>
  F2  = P5E_CPU0_P1_RX_BUF_DP<1>
  F3  = P5E_CPU0_P1_RX_BUF_DN<2>
  F4  = P5E_CPU0_P1_RX_BUF_DP<3>
  F5  = P5E_CPU0_P1_RX_BUF_DN<4>
  F6  = P5E_CPU0_P1_RX_BUF_DP<5>
  F7  = P5E_CPU0_P1_RX_BUF_DN<6>
  F8  = P5E_CPU0_P1_RX_BUF_DP<7>
  G1  = P5E_CPU0_P1_RX_BUF_DP<0>
  G2  = GND
  G3  = P5E_CPU0_P1_RX_BUF_DP<2>
  G4  = GND
  G5  = P5E_CPU0_P1_RX_BUF_DP<4>
  G6  = GND
  G7  = P5E_CPU0_P1_RX_BUF_DP<6>
  G8  = GND
  H1  = GND
  H2  = P5E_CPU0_P0_TX_BUF_C_DN<1>
  H3  = GND
  H4  = P5E_CPU0_P0_TX_BUF_C_DN<3>
  H5  = GND
  H6  = P5E_CPU0_P0_TX_BUF_C_DN<5>
  H7  = GND
  H8  = P5E_CPU0_P0_TX_BUF_C_DN<7>
  I1  = P5E_CPU0_P0_TX_BUF_C_DN<0>
  I2  = P5E_CPU0_P0_TX_BUF_C_DP<1>
  I3  = P5E_CPU0_P0_TX_BUF_C_DN<2>
  I4  = P5E_CPU0_P0_TX_BUF_C_DP<3>
  I5  = P5E_CPU0_P0_TX_BUF_C_DN<4>
  I6  = P5E_CPU0_P0_TX_BUF_C_DP<5>
  I7  = P5E_CPU0_P0_TX_BUF_C_DN<6>
  I8  = P5E_CPU0_P0_TX_BUF_C_DP<7>
  J1  = P5E_CPU0_P0_TX_BUF_C_DP<0>
  J2  = GND
  J3  = P5E_CPU0_P0_TX_BUF_C_DP<2>
  J4  = GND
  J5  = P5E_CPU0_P0_TX_BUF_C_DP<4>
  J6  = GND
  J7  = P5E_CPU0_P0_TX_BUF_C_DP<6>
  J8  = GND
  K1  = GND
  K2  = P5E_CPU0_P1_TX_BUF_C_DN<1>
  K3  = GND
  K4  = P5E_CPU0_P1_TX_BUF_C_DN<3>
  K5  = GND
  K6  = P5E_CPU0_P1_TX_BUF_C_DN<5>
  K7  = GND
  K8  = P5E_CPU0_P1_TX_BUF_C_DN<7>
  L1  = P5E_CPU0_P1_TX_BUF_C_DN<0>
  L2  = P5E_CPU0_P1_TX_BUF_C_DP<1>
  L3  = P5E_CPU0_P1_TX_BUF_C_DN<2>
  L4  = P5E_CPU0_P1_TX_BUF_C_DP<3>
  L5  = P5E_CPU0_P1_TX_BUF_C_DN<4>
  L6  = P5E_CPU0_P1_TX_BUF_C_DP<5>
  L7  = P5E_CPU0_P1_TX_BUF_C_DN<6>
  L8  = P5E_CPU0_P1_TX_BUF_C_DP<7>
  M1  = P5E_CPU0_P1_TX_BUF_C_DP<0>
  M2  = GND
  M3  = P5E_CPU0_P1_TX_BUF_C_DP<2>
  M4  = GND
  M5  = P5E_CPU0_P1_TX_BUF_C_DP<4>
  M6  = GND
  M7  = P5E_CPU0_P1_TX_BUF_C_DP<6>
  M8  = GND
  N1  = GND
  N2  = NC_J108_N2
  N3  = GND
  N4  = NC_J108_N4
  N5  = GND
  N6  = NC_J108_N6
  N7  = GND
  N8  = PRSNT_CABLE_GPU_A3_N

(kicad_pcb
	(version 20260206)
	(generator "pcbnew")
	(generator_version "10.0")
	(general
		(thickness 1.6)
		(legacy_teardrops no)
	)
	(paper "A4")
	(title_block
		(title "04192023_DAF0TMB3IC0_F0TG_MB_C_brd_V02_OCP.brd")
		(comment 1 "Grand Teton / footprint 484 of 8354 (J108), pads 32-48 of 48")
	)
	(layers
		(0 "F.Cu" signal "TOP")
		(4 "In1.Cu" signal "GND")
		(6 "In2.Cu" signal "IN1")
		(8 "In3.Cu" signal "GND1")
		(10 "In4.Cu" signal "IN2")
		(12 "In5.Cu" signal "GND2")
		(14 "In6.Cu" signal "IN3")
		(16 "In7.Cu" signal "GND3")
		(18 "In8.Cu" signal "VCC")
		(20 "In9.Cu" signal "VCC1")
		(22 "In10.Cu" signal "GND4")
		(24 "In11.Cu" signal "IN4")
		(26 "In12.Cu" signal "GND5")
		(28 "In13.Cu" signal "IN5")
		(30 "In14.Cu" signal "GND6")
		(32 "In15.Cu" signal "IN6")
		(34 "In16.Cu" signal "GND7")
		(2 "B.Cu" signal "BOTTOM")
		(9 "F.Adhes" user "F.Adhesive")
		(11 "B.Adhes" user "B.Adhesive")
		(13 "F.Paste" user "Package Geometry/Pastemask Top")
		(15 "B.Paste" user "Package Geometry/Pastemask Bottom")
		(5 "F.SilkS" user "Ref Des/Silkscreen Top")
		(7 "B.SilkS" user "Ref Des/Silkscreen Bottom")
		(1 "F.Mask" user "Board Geometry/Soldermask Top")
		(3 "B.Mask" user "Board Geometry/Soldermask Bottom")
		(17 "Dwgs.User" user "User.Drawings")
		(19 "Cmts.User" user "User.Comments")
		(21 "Eco1.User" user "User.Eco1")
		(23 "Eco2.User" user "User.Eco2")
		(25 "Edge.Cuts" user "Board Geometry/Outline")
		(27 "Margin" user)
		(31 "F.CrtYd" user "Package Geometry/Place Bound Top")
		(29 "B.CrtYd" user "Package Geometry/Place Bound Bottom")
		(35 "F.Fab" user "Ref Des/Assembly Top")
		(33 "B.Fab" user "Ref Des/Assembly Bottom")
	)
	(footprint ""
		(layer "F.Cu")
		(at 314.649612 -440.489848)
		(property "Reference" "J108"
			(at -7.73303 17.692878 0)
			(unlocked yes)
			(layer "F.SilkS")
			(effects
				(font
					(size 0.7874 0.5842)
					(thickness 0.1524)
				)
				(justify left)
			)
		)
		(property "Value" ""
			(at 0 0 0)
			(layer "F.Fab")
			(effects
				(font
					(size 1.27 1.27)
				)
			)
		)
		(duplicate_pad_numbers_are_jumpers no)
		(pad "J8" thru_hole circle
			(at 13.999972 10.999978 180)
			(size 0.906272 0.906272)
			(drill 0.499872)
			(layers "*.Cu" "*.Mask")
			(remove_unused_layers no)
			(net "GND")
			(clearance 0.0508)
			(thermal_gap 0.0508)
		)
		(pad "K1" thru_hole circle
			(at 0 11.999976 180)
			(size 0.906272 0.906272)
			(drill 0.499872)
			(layers "*.Cu" "*.Mask")
			(remove_unused_layers no)
			(net "GND")
			(clearance 0.0508)
			(thermal_gap 0.0508)
		)
		(pad "K3" thru_hole circle
			(at 3.999992 11.999976 180)
			(size 0.906272 0.906272)
			(drill 0.499872)
			(layers "*.Cu" "*.Mask")
			(remove_unused_layers no)
			(net "GND")
			(clearance 0.0508)
			(thermal_gap 0.0508)
		)
		(pad "K5" thru_hole circle
			(at 7.999984 11.999976 180)
			(size 0.906272 0.906272)
			(drill 0.499872)
			(layers "*.Cu" "*.Mask")
			(remove_unused_layers no)
			(net "GND")
			(clearance 0.0508)
			(thermal_gap 0.0508)
		)
		(pad "K7" thru_hole circle
			(at 11.999976 11.999976 180)
			(size 0.906272 0.906272)
			(drill 0.499872)
			(layers "*.Cu" "*.Mask")
			(remove_unused_layers no)
			(net "GND")
			(clearance 0.0508)
			(thermal_gap 0.0508)
		)
		(pad "M2" thru_hole circle
			(at 1.999996 14.59992 180)
			(size 0.906272 0.906272)
			(drill 0.499872)
			(layers "*.Cu" "*.Mask")
			(remove_unused_layers no)
			(net "GND")
			(clearance 0.0508)
			(thermal_gap 0.0508)
		)
		(pad "M4" thru_hole circle
			(at 5.999988 14.59992 180)
			(size 0.906272 0.906272)
			(drill 0.499872)
			(layers "*.Cu" "*.Mask")
			(remove_unused_layers no)
			(net "GND")
			(clearance 0.0508)
			(thermal_gap 0.0508)
		)
		(pad "M6" thru_hole circle
			(at 9.99998 14.59992 180)
			(size 0.906272 0.906272)
			(drill 0.499872)
			(layers "*.Cu" "*.Mask")
			(remove_unused_layers no)
			(net "GND")
			(clearance 0.0508)
			(thermal_gap 0.0508)
		)
		(pad "M8" thru_hole circle
			(at 13.999972 14.59992 180)
			(size 0.906272 0.906272)
			(drill 0.499872)
			(layers "*.Cu" "*.Mask")
			(remove_unused_layers no)
			(net "GND")
			(clearance 0.0508)
			(thermal_gap 0.0508)
		)
		(pad "N1" thru_hole circle
			(at 0 15.599918 180)
			(size 0.906272 0.906272)
			(drill 0.499872)
			(layers "*.Cu" "*.Mask")
			(remove_unused_layers no)
			(net "GND")
			(clearance 0.0508)
			(thermal_gap 0.0508)
		)
		(pad "N2" thru_hole circle
			(at 1.999996 15.80007 180)
			(size 0.766318 0.766318)
			(drill 0.359918)
			(layers "*.Cu" "*.Mask")
			(remove_unused_layers no)
			(net "NC_J108_N2")
			(clearance 0.0508)
			(thermal_gap 0.0508)
		)
		(pad "N3" thru_hole circle
			(at 3.999992 15.599918 180)
			(size 0.906272 0.906272)
			(drill 0.499872)
			(layers "*.Cu" "*.Mask")
			(remove_unused_layers no)
			(net "GND")
			(clearance 0.0508)
			(thermal_gap 0.0508)
		)
		(pad "N4" thru_hole circle
			(at 5.999988 15.80007 180)
			(size 0.766318 0.766318)
			(drill 0.359918)
			(layers "*.Cu" "*.Mask")
			(remove_unused_layers no)
			(net "NC_J108_N4")
			(clearance 0.0508)
			(thermal_gap 0.0508)
		)
		(pad "N5" thru_hole circle
			(at 7.999984 15.599918 180)
			(size 0.906272 0.906272)
			(drill 0.499872)
			(layers "*.Cu" "*.Mask")
			(remove_unused_layers no)
			(net "GND")
			(clearance 0.0508)
			(thermal_gap 0.0508)
		)
		(pad "N6" thru_hole circle
			(at 9.99998 15.80007 180)
			(size 0.766318 0.766318)
			(drill 0.359918)
			(layers "*.Cu" "*.Mask")
			(remove_unused_layers no)
			(net "NC_J108_N6")
			(clearance 0.0508)
			(thermal_gap 0.0508)
		)
		(pad "N7" thru_hole circle
			(at 11.999976 15.599918 180)
			(size 0.906272 0.906272)
			(drill 0.499872)
			(layers "*.Cu" "*.Mask")
			(remove_unused_layers no)
			(net "GND")
			(clearance 0.0508)
			(thermal_gap 0.0508)
		)
		(pad "N8" thru_hole circle
			(at 13.999972 15.80007 180)
			(size 0.766318 0.766318)
			(drill 0.359918)
			(layers "*.Cu" "*.Mask")
			(remove_unused_layers no)
			(net "PRSNT_CABLE_GPU_A3_N")
			(clearance 0.0508)
			(thermal_gap 0.0508)
		)
	)
)
